# T6G (Grand Teton) — schematic netlist excerpt (pin names and nets, part order shuffled) for the footprints in the layout excerpt that follows; sources: Cadence DE-HDL packaged netlist, KiCad conversion of 04192023_DAF0TMB3IC0_F0TG_MB_C_brd_V02_OCP.brd

C624  Q_CAP  1UF 4V 20% X6S  pkg 0201  page 290 : A = P0V9_CPU0_RT1_2A_2D ; B = GND
R2674  Q_RES  27 5% CHIP  pkg 0402LF  page 248 : A = I3C_BMC_SWB_BUF_R_SDA ; B = I3C_BMC_SWB_BUF_SDA
R6750  Q_RES  1K 1% CHIP  pkg 0201LF  page 184 : A = P1V8_CPU1_RT_1D ; B = SMB_RT_CPU1_P3_R_SDA

(kicad_pcb
	(version 20260206)
	(generator "pcbnew")
	(generator_version "10.0")
	(general
		(thickness 1.6)
		(legacy_teardrops no)
	)
	(paper "A4")
	(title_block
		(title "04192023_DAF0TMB3IC0_F0TG_MB_C_brd_V02_OCP.brd")
		(comment 1 "Grand Teton / footprints 7443-7445 of 8354")
	)
	(layers
		(0 "F.Cu" signal "TOP")
		(4 "In1.Cu" signal "GND")
		(6 "In2.Cu" signal "IN1")
		(8 "In3.Cu" signal "GND1")
		(10 "In4.Cu" signal "IN2")
		(12 "In5.Cu" signal "GND2")
		(14 "In6.Cu" signal "IN3")
		(16 "In7.Cu" signal "GND3")
		(18 "In8.Cu" signal "VCC")
		(20 "In9.Cu" signal "VCC1")
		(22 "In10.Cu" signal "GND4")
		(24 "In11.Cu" signal "IN4")
		(26 "In12.Cu" signal "GND5")
		(28 "In13.Cu" signal "IN5")
		(30 "In14.Cu" signal "GND6")
		(32 "In15.Cu" signal "IN6")
		(34 "In16.Cu" signal "GND7")
		(2 "B.Cu" signal "BOTTOM")
		(9 "F.Adhes" user "F.Adhesive")
		(11 "B.Adhes" user "B.Adhesive")
		(13 "F.Paste" user "Package Geometry/Pastemask Top")
		(15 "B.Paste" user "Package Geometry/Pastemask Bottom")
		(5 "F.SilkS" user "Ref Des/Silkscreen Top")
		(7 "B.SilkS" user "Ref Des/Silkscreen Bottom")
		(1 "F.Mask" user "Board Geometry/Soldermask Top")
		(3 "B.Mask" user "Board Geometry/Soldermask Bottom")
		(17 "Dwgs.User" user "User.Drawings")
		(19 "Cmts.User" user "User.Comments")
		(21 "Eco1.User" user "User.Eco1")
		(23 "Eco2.User" user "User.Eco2")
		(25 "Edge.Cuts" user "Board Geometry/Outline")
		(27 "Margin" user)
		(31 "F.CrtYd" user "Package Geometry/Place Bound Top")
		(29 "B.CrtYd" user "Package Geometry/Place Bound Bottom")
		(35 "F.Fab" user "Ref Des/Assembly Top")
		(33 "B.Fab" user "Ref Des/Assembly Bottom")
	)
	(footprint ""
		(layer "B.Cu")
		(at 289.941 -426.466)
		(property "Reference" "R2674"
			(at 0 0 0)
			(layer "B.SilkS")
			(hide yes)
			(effects
				(font
					(size 1.27 1.27)
				)
				(justify mirror)
			)
		)
		(property "Value" ""
			(at 0 0 0)
			(layer "B.Fab")
			(effects
				(font
					(size 1.27 1.27)
				)
				(justify mirror)
			)
		)
		(duplicate_pad_numbers_are_jumpers no)
		(fp_line
			(start -0.7874 -0.4064)
			(end -0.7874 0.4064)
			(stroke
				(width 0.1524)
				(type default)
			)
			(layer "B.SilkS")
		)
		(fp_line
			(start -0.7874 0.4064)
			(end 0.7874 0.4064)
			(stroke
				(width 0.1524)
				(type default)
			)
			(layer "B.SilkS")
		)
		(fp_line
			(start 0.7874 -0.4064)
			(end -0.7874 -0.4064)
			(stroke
				(width 0.1524)
				(type default)
			)
			(layer "B.SilkS")
		)
		(fp_line
			(start 0.7874 0.4064)
			(end 0.7874 -0.4064)
			(stroke
				(width 0.1524)
				(type default)
			)
			(layer "B.SilkS")
		)
		(fp_line
			(start -0.67945 -0.3048)
			(end -0.67945 0.3048)
			(stroke
				(width 0.1)
				(type default)
			)
			(layer "B.Fab")
		)
		(fp_line
			(start -0.67945 0.3048)
			(end -0.120396 0.3048)
			(stroke
				(width 0.1)
				(type default)
			)
			(layer "B.Fab")
		)
		(fp_line
			(start -0.12065 -0.3048)
			(end -0.67945 -0.3048)
			(stroke
				(width 0.1)
				(type default)
			)
			(layer "B.Fab")
		)
		(fp_line
			(start -0.12065 -0.2794)
			(end -0.12065 -0.3048)
			(stroke
				(width 0.1)
				(type default)
			)
			(layer "B.Fab")
		)
		(fp_line
			(start -0.120396 0.2794)
			(end 0.12065 0.2794)
			(stroke
				(width 0.1)
				(type default)
			)
			(layer "B.Fab")
		)
		(fp_line
			(start -0.120396 0.3048)
			(end -0.120396 0.2794)
			(stroke
				(width 0.1)
				(type default)
			)
			(layer "B.Fab")
		)
		(fp_line
			(start 0.12065 -0.305054)
			(end 0.12065 -0.2794)
			(stroke
				(width 0.1)
				(type default)
			)
			(layer "B.Fab")
		)
		(fp_line
			(start 0.12065 -0.2794)
			(end -0.12065 -0.2794)
			(stroke
				(width 0.1)
				(type default)
			)
			(layer "B.Fab")
		)
		(fp_line
			(start 0.12065 0.2794)
			(end 0.12065 0.3048)
			(stroke
				(width 0.1)
				(type default)
			)
			(layer "B.Fab")
		)
		(fp_line
			(start 0.12065 0.3048)
			(end 0.67945 0.3048)
			(stroke
				(width 0.1)
				(type default)
			)
			(layer "B.Fab")
		)
		(fp_line
			(start 0.67945 -0.305054)
			(end 0.12065 -0.305054)
			(stroke
				(width 0.1)
				(type default)
			)
			(layer "B.Fab")
		)
		(fp_line
			(start 0.67945 0.3048)
			(end 0.67945 -0.305054)
			(stroke
				(width 0.1)
				(type default)
			)
			(layer "B.Fab")
		)
		(pad "1" smd circle
			(at 0.40005 0 180)
			(size 0 0)
			(layers "B.Cu" "B.Mask" "B.Paste")
			(net "I3C_BMC_SWB_BUF_R_SDA")
		)
		(pad "2" smd circle
			(at -0.40005 0 180)
			(size 0 0)
			(layers "B.Cu" "B.Mask" "B.Paste")
			(net "I3C_BMC_SWB_BUF_SDA")
		)
	)
	(footprint ""
		(layer "B.Cu")
		(at 216.027 -338.455 -90)
		(property "Reference" "R6750"
			(at 0 0 90)
			(layer "B.SilkS")
			(hide yes)
			(effects
				(font
					(size 1.27 1.27)
				)
				(justify mirror)
			)
		)
		(property "Value" ""
			(at 0 0 90)
			(layer "B.Fab")
			(effects
				(font
					(size 1.27 1.27)
				)
				(justify mirror)
			)
		)
		(duplicate_pad_numbers_are_jumpers no)
		(fp_line
			(start -0.32512 0.175006)
			(end 0.32512 0.175006)
			(stroke
				(width 0.1)
				(type default)
			)
			(layer "B.Fab")
		)
		(fp_line
			(start 0.32512 0.175006)
			(end 0.32512 -0.175006)
			(stroke
				(width 0.1)
				(type default)
			)
			(layer "B.Fab")
		)
		(fp_line
			(start -0.32512 -0.175006)
			(end -0.32512 0.175006)
			(stroke
				(width 0.1)
				(type default)
			)
			(layer "B.Fab")
		)
		(fp_line
			(start 0.32512 -0.175006)
			(end -0.32512 -0.175006)
			(stroke
				(width 0.1)
				(type default)
			)
			(layer "B.Fab")
		)
		(pad "1" smd rect
			(at 0.2667 0 90)
			(size 0.3048 0.381)
			(layers "B.Cu" "B.Mask" "B.Paste")
			(net "P1V8_CPU1_RT_1D")
		)
		(pad "2" smd rect
			(at -0.2667 0 270)
			(size 0.3048 0.381)
			(layers "B.Cu" "B.Mask" "B.Paste")
			(net "SMB_RT_CPU1_P3_R_SDA")
		)
	)
	(footprint ""
		(layer "B.Cu")
		(at 349.105982 -395.148562 90)
		(property "Reference" "C624"
			(at 0 0 90)
			(layer "B.SilkS")
			(hide yes)
			(effects
				(font
					(size 1.27 1.27)
				)
				(justify mirror)
			)
		)
		(property "Value" ""
			(at 0 0 90)
			(layer "B.Fab")
			(effects
				(font
					(size 1.27 1.27)
				)
				(justify mirror)
			)
		)
		(duplicate_pad_numbers_are_jumpers no)
		(fp_line
			(start 0.299974 -0.150114)
			(end -0.299974 -0.150114)
			(stroke
				(width 0.1)
				(type default)
			)
			(layer "B.Fab")
		)
		(fp_line
			(start -0.299974 -0.150114)
			(end -0.299974 0.150114)
			(stroke
				(width 0.1)
				(type default)
			)
			(layer "B.Fab")
		)
		(fp_line
			(start 0.299974 0.150114)
			(end 0.299974 -0.150114)
			(stroke
				(width 0.1)
				(type default)
			)
			(layer "B.Fab")
		)
		(fp_line
			(start -0.299974 0.150114)
			(end 0.299974 0.150114)
			(stroke
				(width 0.1)
				(type default)
			)
			(layer "B.Fab")
		)
		(pad "1" smd rect
			(at 0.2667 0 270)
			(size 0.3048 0.381)
			(layers "B.Cu" "B.Mask" "B.Paste")
			(net "P0V9_CPU0_RT1_2A_2D")
		)
		(pad "2" smd rect
			(at -0.2667 0 270)
			(size 0.3048 0.381)
			(layers "B.Cu" "B.Mask" "B.Paste")
			(net "GND")
		)
	)
)
